# S9S_MB_2U (Grand Teton) — schematic netlist excerpt (pin names and nets, part order shuffled) for the footprints in the layout excerpt that follows; sources: Cadence DE-HDL packaged netlist, KiCad conversion of 03242023_DA0F0TMBIJ0_F0T_Motherboard_J_brd_V01_OCP.brd

C5  Q_CAP  2.2UF 6.3V 20% X6S  pkg C0402  page 83 : A = P3V3_AUX ; B = GND
C518  Q_CAP  47UF 4V 20% X6S  pkg C0805  page 75 : A = PVCCD_HV_CPU0 ; B = GND
R1406  Q_RES  2K 1% CHIP  pkg 0402LF  page 219 : A = FM_PVCCIN_CPU1_R_EN ; B = GND

(kicad_pcb
	(version 20260206)
	(generator "pcbnew")
	(generator_version "10.0")
	(general
		(thickness 1.6)
		(legacy_teardrops no)
	)
	(paper "A4")
	(title_block
		(title "03242023_DA0F0TMBIJ0_F0T_Motherboard_J_brd_V01_OCP.brd")
		(comment 1 "Grand Teton / footprints 5363-5365 of 6105")
	)
	(layers
		(0 "F.Cu" signal "TOP")
		(4 "In1.Cu" signal "GND")
		(6 "In2.Cu" signal "IN1")
		(8 "In3.Cu" signal "GND1")
		(10 "In4.Cu" signal "IN2")
		(12 "In5.Cu" signal "GND2")
		(14 "In6.Cu" signal "IN3")
		(16 "In7.Cu" signal "GND3")
		(18 "In8.Cu" signal "VCC")
		(20 "In9.Cu" signal "VCC1")
		(22 "In10.Cu" signal "GND4")
		(24 "In11.Cu" signal "IN4")
		(26 "In12.Cu" signal "GND5")
		(28 "In13.Cu" signal "IN5")
		(30 "In14.Cu" signal "GND6")
		(32 "In15.Cu" signal "IN6")
		(34 "In16.Cu" signal "GND7")
		(2 "B.Cu" signal "BOTTOM")
		(9 "F.Adhes" user "F.Adhesive")
		(11 "B.Adhes" user "B.Adhesive")
		(13 "F.Paste" user "Package Geometry/Pastemask Top")
		(15 "B.Paste" user "Package Geometry/Pastemask Bottom")
		(5 "F.SilkS" user "Ref Des/Silkscreen Top")
		(7 "B.SilkS" user "Ref Des/Silkscreen Bottom")
		(1 "F.Mask" user "Board Geometry/Soldermask Top")
		(3 "B.Mask" user "Board Geometry/Soldermask Bottom")
		(17 "Dwgs.User" user "User.Drawings")
		(19 "Cmts.User" user "User.Comments")
		(21 "Eco1.User" user "User.Eco1")
		(23 "Eco2.User" user "User.Eco2")
		(25 "Edge.Cuts" user "Board Geometry/Outline")
		(27 "Margin" user)
		(31 "F.CrtYd" user "Package Geometry/Place Bound Top")
		(29 "B.CrtYd" user "Package Geometry/Place Bound Bottom")
		(35 "F.Fab" user "Ref Des/Assembly Top")
		(33 "B.Fab" user "Ref Des/Assembly Bottom")
	)
	(footprint ""
		(layer "B.Cu")
		(at 307.16601 -317.306452 90)
		(property "Reference" "C5"
			(at 0 0 90)
			(layer "B.SilkS")
			(hide yes)
			(effects
				(font
					(size 1.27 1.27)
				)
				(justify mirror)
			)
		)
		(property "Value" ""
			(at 0 0 90)
			(layer "B.Fab")
			(effects
				(font
					(size 1.27 1.27)
				)
				(justify mirror)
			)
		)
		(duplicate_pad_numbers_are_jumpers no)
		(fp_line
			(start 0.7874 -0.4064)
			(end -0.7874 -0.4064)
			(stroke
				(width 0.1524)
				(type default)
			)
			(layer "B.SilkS")
		)
		(fp_line
			(start -0.7874 -0.4064)
			(end -0.7874 0.4064)
			(stroke
				(width 0.1524)
				(type default)
			)
			(layer "B.SilkS")
		)
		(fp_line
			(start 0.7874 0.4064)
			(end 0.7874 -0.4064)
			(stroke
				(width 0.1524)
				(type default)
			)
			(layer "B.SilkS")
		)
		(fp_line
			(start -0.7874 0.4064)
			(end 0.7874 0.4064)
			(stroke
				(width 0.1524)
				(type default)
			)
			(layer "B.SilkS")
		)
		(fp_line
			(start 0.67945 -0.305054)
			(end 0.12065 -0.305054)
			(stroke
				(width 0.1)
				(type default)
			)
			(layer "B.Fab")
		)
		(fp_line
			(start 0.12065 -0.305054)
			(end 0.12065 -0.2794)
			(stroke
				(width 0.1)
				(type default)
			)
			(layer "B.Fab")
		)
		(fp_line
			(start -0.12065 -0.3048)
			(end -0.67945 -0.3048)
			(stroke
				(width 0.1)
				(type default)
			)
			(layer "B.Fab")
		)
		(fp_line
			(start -0.67945 -0.3048)
			(end -0.67945 0.3048)
			(stroke
				(width 0.1)
				(type default)
			)
			(layer "B.Fab")
		)
		(fp_line
			(start 0.12065 -0.2794)
			(end -0.12065 -0.2794)
			(stroke
				(width 0.1)
				(type default)
			)
			(layer "B.Fab")
		)
		(fp_line
			(start -0.12065 -0.2794)
			(end -0.12065 -0.3048)
			(stroke
				(width 0.1)
				(type default)
			)
			(layer "B.Fab")
		)
		(fp_line
			(start 0.12065 0.2794)
			(end 0.12065 0.3048)
			(stroke
				(width 0.1)
				(type default)
			)
			(layer "B.Fab")
		)
		(fp_line
			(start -0.120396 0.2794)
			(end 0.12065 0.2794)
			(stroke
				(width 0.1)
				(type default)
			)
			(layer "B.Fab")
		)
		(fp_line
			(start 0.67945 0.3048)
			(end 0.67945 -0.305054)
			(stroke
				(width 0.1)
				(type default)
			)
			(layer "B.Fab")
		)
		(fp_line
			(start 0.12065 0.3048)
			(end 0.67945 0.3048)
			(stroke
				(width 0.1)
				(type default)
			)
			(layer "B.Fab")
		)
		(fp_line
			(start -0.120396 0.3048)
			(end -0.120396 0.2794)
			(stroke
				(width 0.1)
				(type default)
			)
			(layer "B.Fab")
		)
		(fp_line
			(start -0.67945 0.3048)
			(end -0.120396 0.3048)
			(stroke
				(width 0.1)
				(type default)
			)
			(layer "B.Fab")
		)
		(pad "1" smd circle
			(at 0.40005 0 270)
			(size 0 0)
			(layers "B.Cu" "B.Mask" "B.Paste")
			(net "P3V3_AUX")
		)
		(pad "2" smd circle
			(at -0.40005 0 270)
			(size 0 0)
			(layers "B.Cu" "B.Mask" "B.Paste")
			(net "GND")
		)
	)
	(footprint ""
		(layer "B.Cu")
		(at 351.928938 -241.19967 90)
		(property "Reference" "C518"
			(at 0 0 90)
			(layer "B.SilkS")
			(hide yes)
			(effects
				(font
					(size 1.27 1.27)
				)
				(justify mirror)
			)
		)
		(property "Value" ""
			(at 0 0 90)
			(layer "B.Fab")
			(effects
				(font
					(size 1.27 1.27)
				)
				(justify mirror)
			)
		)
		(duplicate_pad_numbers_are_jumpers no)
		(fp_line
			(start 1.524 -0.762)
			(end -1.524 -0.762)
			(stroke
				(width 0.1524)
				(type default)
			)
			(layer "B.SilkS")
		)
		(fp_line
			(start -1.524 -0.762)
			(end -1.524 0.762)
			(stroke
				(width 0.1524)
				(type default)
			)
			(layer "B.SilkS")
		)
		(fp_line
			(start 1.524 0.762)
			(end 1.524 -0.762)
			(stroke
				(width 0.1524)
				(type default)
			)
			(layer "B.SilkS")
		)
		(fp_line
			(start -1.524 0.762)
			(end 1.524 0.762)
			(stroke
				(width 0.1524)
				(type default)
			)
			(layer "B.SilkS")
		)
		(fp_line
			(start 1.1049 -0.724916)
			(end 1.1049 0.724916)
			(stroke
				(width 0.1)
				(type default)
			)
			(layer "B.Fab")
		)
		(fp_line
			(start -1.1049 -0.724916)
			(end 1.1049 -0.724916)
			(stroke
				(width 0.1)
				(type default)
			)
			(layer "B.Fab")
		)
		(fp_line
			(start 1.1049 0.724916)
			(end -1.1049 0.724916)
			(stroke
				(width 0.1)
				(type default)
			)
			(layer "B.Fab")
		)
		(fp_line
			(start -1.1049 0.724916)
			(end -1.1049 -0.724916)
			(stroke
				(width 0.1)
				(type default)
			)
			(layer "B.Fab")
		)
		(pad "1" smd rect
			(at 0.889 0 90)
			(size 1.016 1.27)
			(layers "B.Cu" "B.Mask" "B.Paste")
			(net "PVCCD_HV_CPU0")
		)
		(pad "2" smd rect
			(at -0.889 0 90)
			(size 1.016 1.27)
			(layers "B.Cu" "B.Mask" "B.Paste")
			(net "GND")
		)
	)
	(footprint ""
		(layer "B.Cu")
		(at 164.64788 -120.106948)
		(property "Reference" "R1406"
			(at 0 0 0)
			(layer "B.SilkS")
			(hide yes)
			(effects
				(font
					(size 1.27 1.27)
				)
				(justify mirror)
			)
		)
		(property "Value" ""
			(at 0 0 0)
			(layer "B.Fab")
			(effects
				(font
					(size 1.27 1.27)
				)
				(justify mirror)
			)
		)
		(duplicate_pad_numbers_are_jumpers no)
		(fp_line
			(start -0.7874 -0.4064)
			(end -0.7874 0.4064)
			(stroke
				(width 0.1524)
				(type default)
			)
			(layer "B.SilkS")
		)
		(fp_line
			(start -0.7874 0.4064)
			(end 0.7874 0.4064)
			(stroke
				(width 0.1524)
				(type default)
			)
			(layer "B.SilkS")
		)
		(fp_line
			(start 0.7874 -0.4064)
			(end -0.7874 -0.4064)
			(stroke
				(width 0.1524)
				(type default)
			)
			(layer "B.SilkS")
		)
		(fp_line
			(start 0.7874 0.4064)
			(end 0.7874 -0.4064)
			(stroke
				(width 0.1524)
				(type default)
			)
			(layer "B.SilkS")
		)
		(fp_line
			(start -0.67945 -0.3048)
			(end -0.67945 0.3048)
			(stroke
				(width 0.1)
				(type default)
			)
			(layer "B.Fab")
		)
		(fp_line
			(start -0.67945 0.3048)
			(end -0.120396 0.3048)
			(stroke
				(width 0.1)
				(type default)
			)
			(layer "B.Fab")
		)
		(fp_line
			(start -0.12065 -0.3048)
			(end -0.67945 -0.3048)
			(stroke
				(width 0.1)
				(type default)
			)
			(layer "B.Fab")
		)
		(fp_line
			(start -0.12065 -0.2794)
			(end -0.12065 -0.3048)
			(stroke
				(width 0.1)
				(type default)
			)
			(layer "B.Fab")
		)
		(fp_line
			(start -0.120396 0.2794)
			(end 0.12065 0.2794)
			(stroke
				(width 0.1)
				(type default)
			)
			(layer "B.Fab")
		)
		(fp_line
			(start -0.120396 0.3048)
			(end -0.120396 0.2794)
			(stroke
				(width 0.1)
				(type default)
			)
			(layer "B.Fab")
		)
		(fp_line
			(start 0.12065 -0.305054)
			(end 0.12065 -0.2794)
			(stroke
				(width 0.1)
				(type default)
			)
			(layer "B.Fab")
		)
		(fp_line
			(start 0.12065 -0.2794)
			(end -0.12065 -0.2794)
			(stroke
				(width 0.1)
				(type default)
			)
			(layer "B.Fab")
		)
		(fp_line
			(start 0.12065 0.2794)
			(end 0.12065 0.3048)
			(stroke
				(width 0.1)
				(type default)
			)
			(layer "B.Fab")
		)
		(fp_line
			(start 0.12065 0.3048)
			(end 0.67945 0.3048)
			(stroke
				(width 0.1)
				(type default)
			)
			(layer "B.Fab")
		)
		(fp_line
			(start 0.67945 -0.305054)
			(end 0.12065 -0.305054)
			(stroke
				(width 0.1)
				(type default)
			)
			(layer "B.Fab")
		)
		(fp_line
			(start 0.67945 0.3048)
			(end 0.67945 -0.305054)
			(stroke
				(width 0.1)
				(type default)
			)
			(layer "B.Fab")
		)
		(pad "1" smd circle
			(at 0.40005 0 180)
			(size 0 0)
			(layers "B.Cu" "B.Mask" "B.Paste")
			(net "FM_PVCCIN_CPU1_R_EN")
		)
		(pad "2" smd circle
			(at -0.40005 0 180)
			(size 0 0)
			(layers "B.Cu" "B.Mask" "B.Paste")
			(net "GND")
		)
	)
)
